FILE_TYPE = MULTI_PHYS_TABLE;
PART 'TPS54821'
{===============================================================================================================================================================================================================}
: PACK_TYPE | MATERIAL | PART_NUMBER     = EnvComp | PART_NUMBER  | JEDEC_TYPE     | DESCRIPTION                     | CLASS | COMPONENT_TYPE | HEIGHT     | LPID   | SPEED_URL | Status |RPL| AML | Bus_Unit | Days;
{===============================================================================================================================================================================================================}
'LCC'      | 'IC'     | 'H63269-001'(!) = ''      | 'H63269-001' | 'LCC14_14_5MA' | 'IC,LIN,QFN,TPS54821,SWITCHING' | 'IC'  | 'LCC'          | '0.039 IN' | '1956' | 'http://speed.intel.com:8081/speed/module/pdm/item/pdm_item_detail_direct.asp?item_cde=H63269-001&item_rev=01&url_param=unused' | '' | '' | '' | '' | '' 
'LCC'      | 'EMPTY'  | 'H63269-001'(!) = ''      | 'H63269-001' | 'LCC14_14_5MA' | 'IC,LIN,QFN,TPS54821,SWITCHING' | 'IO'  | 'LCC'          | '0.039 IN' | '1956' | 'http://speed.intel.com:8081/speed/module/pdm/item/pdm_item_detail_direct.asp?item_cde=H63269-001&item_rev=01&url_param=unused' | '' | '' | '' | '' | '' 
END_PART
END.
